(kicad_pcb
	(version 20260206)
	(generator "pcbnew")
	(generator_version "10.0")
	(general
		(thickness 1.6)
		(legacy_teardrops no)
	)
	(paper "A4")
	(title_block
		(title "Bryce Canyon_SCC_16316-1_OCP.brd")
		(comment 1 "Bryce Canyon / footprints 258-264 of 1561")
	)
	(layers
		(0 "F.Cu" signal "TOP")
		(4 "In1.Cu" signal "L2GND")
		(6 "In2.Cu" signal "L3")
		(8 "In3.Cu" signal "L4VCC")
		(10 "In4.Cu" signal "L5VCC")
		(12 "In5.Cu" signal "L6")
		(14 "In6.Cu" signal "L7GND")
		(2 "B.Cu" signal "BOTTOM")
		(9 "F.Adhes" user "F.Adhesive")
		(11 "B.Adhes" user "B.Adhesive")
		(13 "F.Paste" user "Package Geometry/Pastemask Top")
		(15 "B.Paste" user "Package Geometry/Pastemask Bottom")
		(5 "F.SilkS" user "Ref Des/Silkscreen Top")
		(7 "B.SilkS" user "Ref Des/Silkscreen Bottom")
		(1 "F.Mask" user "Board Geometry/Soldermask Top")
		(3 "B.Mask" user "Board Geometry/Soldermask Bottom")
		(17 "Dwgs.User" user "User.Drawings")
		(19 "Cmts.User" user "User.Comments")
		(21 "Eco1.User" user "User.Eco1")
		(23 "Eco2.User" user "User.Eco2")
		(25 "Edge.Cuts" user "Board Geometry/Outline")
		(27 "Margin" user)
		(31 "F.CrtYd" user "Package Geometry/Place Bound Top")
		(29 "B.CrtYd" user "Package Geometry/Place Bound Bottom")
		(35 "F.Fab" user "Ref Des/Assembly Top")
		(33 "B.Fab" user "Ref Des/Assembly Bottom")
	)
	(footprint ""
		(layer "F.Cu")
		(at 180.436012 -24.040846 90)
		(property "Reference" "VIA8"
			(at 0 0 90)
			(layer "F.SilkS")
			(hide yes)
			(effects
				(font
					(size 1.27 1.27)
				)
			)
		)
		(property "Value" "85OHM-8L-1D6MM-L16L18-GP"
			(at 4.064 0.6096 90)
			(unlocked yes)
			(layer "F.Fab")
			(hide yes)
			(effects
				(font
					(size 1.016 1.016)
					(thickness 0.1524)
				)
			)
		)
		(property "Device Type" "VIA-PCIE-4P-368076"
			(at 4.064 -0.9144 90)
			(unlocked yes)
			(layer "F.Fab")
			(hide yes)
			(effects
				(font
					(size 1.016 1.016)
					(thickness 0.1524)
				)
			)
		)
		(duplicate_pad_numbers_are_jumpers no)
		(fp_rect
			(start -1.8415 0.381)
			(end 1.8415 -0.381)
			(stroke
				(width 0)
				(type default)
			)
			(fill no)
			(layer "F.CrtYd")
		)
		(fp_rect
			(start -1.8415 0.381)
			(end 1.8415 -0.381)
			(stroke
				(width 0)
				(type default)
			)
			(fill no)
			(layer "F.Fab")
		)
		(pad "1" thru_hole circle
			(at -1.4605 0 90)
			(size 0.508 0.508)
			(drill 0.254)
			(layers "*.Cu" "*.Mask")
			(remove_unused_layers no)
			(net "GND")
			(clearance 0.127)
			(thermal_gap 0.127)
		)
		(pad "2" thru_hole circle
			(at -0.4445 0 90)
			(size 0.508 0.508)
			(drill 0.254)
			(layers "*.Cu" "*.Mask")
			(remove_unused_layers no)
			(net "PCIE_COMP_TO_SCC_7_DP")
			(clearance 0.127)
			(thermal_gap 0.127)
		)
		(pad "3" thru_hole circle
			(at 0.4445 0 90)
			(size 0.508 0.508)
			(drill 0.254)
			(layers "*.Cu" "*.Mask")
			(remove_unused_layers no)
			(net "PCIE_COMP_TO_SCC_7_DN")
			(clearance 0.127)
			(thermal_gap 0.127)
		)
		(pad "4" thru_hole circle
			(at 1.4605 0 90)
			(size 0.508 0.508)
			(drill 0.254)
			(layers "*.Cu" "*.Mask")
			(remove_unused_layers no)
			(net "GND")
			(clearance 0.127)
			(thermal_gap 0.127)
		)
	)
	(footprint ""
		(layer "F.Cu")
		(at 136.181592 -77.830934 90)
		(property "Reference" "C681"
			(at 0 0 90)
			(layer "F.SilkS")
			(hide yes)
			(effects
				(font
					(size 1.27 1.27)
				)
			)
		)
		(property "Value" "SCD01U16V1KX-GP"
			(at -2.8321 -1.7399 90)
			(unlocked yes)
			(layer "F.Fab")
			(hide yes)
			(effects
				(font
					(size 1.016 1.016)
					(thickness 0.1524)
				)
			)
		)
		(property "Device Type" "C0201H13"
			(at -2.8321 -3.2639 90)
			(unlocked yes)
			(layer "F.Fab")
			(hide yes)
			(effects
				(font
					(size 1.016 1.016)
					(thickness 0.1524)
				)
			)
		)
		(duplicate_pad_numbers_are_jumpers no)
		(fp_rect
			(start -0.2794 0.6477)
			(end 0.2794 -0.6477)
			(stroke
				(width 0)
				(type default)
			)
			(fill no)
			(layer "F.CrtYd")
		)
		(fp_rect
			(start -0.2794 0.6477)
			(end 0.2794 -0.6477)
			(stroke
				(width 0)
				(type default)
			)
			(fill no)
			(layer "F.Fab")
		)
		(pad "1" smd custom
			(at 0 -0.2794 90)
			(size 0.0762 0.0762)
			(layers "F.Cu" "F.Mask" "F.Paste")
			(net "PHY_EXP_TO_CONN_C_9_DN")
			(options
				(clearance outline)
				(anchor circle)
			)
			(primitives
				(gr_poly
					(pts
						(arc
							(start 0.1524 -0.127)
							(mid 0.137521 -0.162921)
							(end 0.1016 -0.1778)
						)
						(arc
							(start -0.1016 -0.1778)
							(mid -0.137521 -0.162921)
							(end -0.1524 -0.127)
						)
						(arc
							(start -0.1524 0.127)
							(mid -0.137521 0.162921)
							(end -0.1016 0.1778)
						)
						(arc
							(start 0.1016 0.1778)
							(mid 0.137521 0.162921)
							(end 0.1524 0.127)
						)
					)
					(width 0)
					(fill yes)
				)
			)
		)
		(pad "2" smd custom
			(at 0 0.2794 90)
			(size 0.0762 0.0762)
			(layers "F.Cu" "F.Mask" "F.Paste")
			(net "PHY_EXP_TO_CONN_9_DN")
			(options
				(clearance outline)
				(anchor circle)
			)
			(primitives
				(gr_poly
					(pts
						(arc
							(start 0.1524 -0.127)
							(mid 0.137521 -0.162921)
							(end 0.1016 -0.1778)
						)
						(arc
							(start -0.1016 -0.1778)
							(mid -0.137521 -0.162921)
							(end -0.1524 -0.127)
						)
						(arc
							(start -0.1524 0.127)
							(mid -0.137521 0.162921)
							(end -0.1016 0.1778)
						)
						(arc
							(start 0.1016 0.1778)
							(mid 0.137521 0.162921)
							(end 0.1524 0.127)
						)
					)
					(width 0)
					(fill yes)
				)
			)
		)
	)
	(footprint ""
		(layer "F.Cu")
		(at 197.23608 -87.4522 180)
		(property "Reference" "DEBUG2"
			(at 0 0 180)
			(layer "F.SilkS")
			(hide yes)
			(effects
				(font
					(size 1.27 1.27)
				)
			)
		)
		(property "Value" "AMP-CONN4D-2-GP"
			(at -6.35 -0.254 180)
			(unlocked yes)
			(layer "F.Fab")
			(hide yes)
			(effects
				(font
					(size 1.016 1.016)
					(thickness 0.1524)
				)
			)
		)
		(property "Device Type" "G800MR304010HR"
			(at -6.35 -1.778 180)
			(unlocked yes)
			(layer "F.Fab")
			(hide yes)
			(effects
				(font
					(size 1.016 1.016)
					(thickness 0.1524)
				)
			)
		)
		(duplicate_pad_numbers_are_jumpers no)
		(fp_line
			(start 5.334 3.2512)
			(end 5.334 -3.2512)
			(stroke
				(width 0.1524)
				(type default)
			)
			(layer "F.SilkS")
		)
		(fp_line
			(start 5.334 -3.2512)
			(end -5.334 -3.2512)
			(stroke
				(width 0.1524)
				(type default)
			)
			(layer "F.SilkS")
		)
		(fp_line
			(start -4.2672 -3.3401)
			(end -3.2512 -3.3401)
			(stroke
				(width 0.3302)
				(type default)
			)
			(layer "F.SilkS")
		)
		(fp_line
			(start -5.334 3.2512)
			(end 5.334 3.2512)
			(stroke
				(width 0.1524)
				(type default)
			)
			(layer "F.SilkS")
		)
		(fp_line
			(start -5.334 -3.2512)
			(end -5.334 3.2512)
			(stroke
				(width 0.1524)
				(type default)
			)
			(layer "F.SilkS")
		)
		(fp_poly
			(pts
				(xy -3.81 -3.3274) (xy -3.175 -3.9624) (xy -4.445 -3.9624)
			)
			(stroke
				(width 0)
				(type default)
			)
			(fill yes)
			(layer "F.SilkS")
		)
		(fp_rect
			(start -5.08 2.4892)
			(end 5.08 -2.4892)
			(stroke
				(width 0)
				(type default)
			)
			(fill no)
			(layer "F.CrtYd")
		)
		(fp_poly
			(pts
				(xy 5.588 -2.4892) (xy -5.08 -2.4892) (xy -5.08 2.4892) (xy 5.08 2.4892) (xy 5.08 -2.4765) (xy 5.588 -2.4765)
				(xy 5.588 3.5052) (xy -5.588 3.5052) (xy -5.588 -3.5052) (xy 5.588 -3.5052)
			)
			(stroke
				(width 0)
				(type default)
			)
			(fill no)
			(layer "F.CrtYd")
		)
		(fp_rect
			(start -5.588 3.5052)
			(end 5.588 -3.5052)
			(stroke
				(width 0)
				(type default)
			)
			(fill no)
			(layer "F.Fab")
		)
		(pad "1" smd rect
			(at -3.81 -1.500124 180)
			(size 0.9906 2.9972)
			(layers "F.Cu" "F.Mask" "F.Paste")
			(net "SDB_CONN_PWR_3")
		)
		(pad "2" smd rect
			(at -1.27 1.500124 180)
			(size 0.9906 2.9972)
			(layers "F.Cu" "F.Mask" "F.Paste")
			(net "UART_IOC_TX")
		)
		(pad "3" smd rect
			(at 1.27 -1.500124 180)
			(size 0.9906 2.9972)
			(layers "F.Cu" "F.Mask" "F.Paste")
			(net "UART_IOC_RX")
		)
		(pad "4" smd rect
			(at 3.81 1.500124 180)
			(size 0.9906 2.9972)
			(layers "F.Cu" "F.Mask" "F.Paste")
			(net "GND")
		)
	)
	(footprint ""
		(layer "F.Cu")
		(at 158.369 -70.80123 90)
		(property "Reference" "R353"
			(at 0 0 90)
			(layer "F.SilkS")
			(hide yes)
			(effects
				(font
					(size 1.27 1.27)
				)
			)
		)
		(property "Value" "1KR2F-3-GP"
			(at 0.064008 -3.993896 90)
			(unlocked yes)
			(layer "F.Fab")
			(hide yes)
			(effects
				(font
					(size 1.016 1.016)
					(thickness 0.1524)
				)
			)
		)
		(property "Device Type" "R402H16"
			(at 0.064008 -5.517896 90)
			(unlocked yes)
			(layer "F.Fab")
			(hide yes)
			(effects
				(font
					(size 1.016 1.016)
					(thickness 0.1524)
				)
			)
		)
		(duplicate_pad_numbers_are_jumpers no)
		(fp_line
			(start 0.508 -0.9398)
			(end -0.508 -0.9398)
			(stroke
				(width 0.1524)
				(type default)
			)
			(layer "F.SilkS")
		)
		(fp_line
			(start -0.508 -0.9398)
			(end -0.508 0.9398)
			(stroke
				(width 0.1524)
				(type default)
			)
			(layer "F.SilkS")
		)
		(fp_rect
			(start -0.508 0.9398)
			(end 0.508 -0.9398)
			(stroke
				(width 0)
				(type default)
			)
			(fill no)
			(layer "F.CrtYd")
		)
		(fp_rect
			(start -0.508 0.9398)
			(end 0.508 -0.9398)
			(stroke
				(width 0)
				(type default)
			)
			(fill no)
			(layer "F.Fab")
		)
		(pad "1" smd custom
			(at 0 -0.4445 90)
			(size 0.1397 0.1397)
			(layers "F.Cu" "F.Mask" "F.Paste")
			(net "P1V5_C")
			(options
				(clearance outline)
				(anchor circle)
			)
			(primitives
				(gr_poly
					(pts
						(arc
							(start -0.1778 -0.2794)
							(mid -0.249642 -0.249642)
							(end -0.2794 -0.1778)
						)
						(arc
							(start -0.2794 0.1778)
							(mid -0.249642 0.249642)
							(end -0.1778 0.2794)
						)
						(arc
							(start 0.1778 0.2794)
							(mid 0.249642 0.249642)
							(end 0.2794 0.1778)
						)
						(arc
							(start 0.2794 -0.1778)
							(mid 0.249642 -0.249642)
							(end 0.1778 -0.2794)
						)
					)
					(width 0)
					(fill yes)
				)
			)
		)
		(pad "2" smd custom
			(at 0 0.4445 90)
			(size 0.1397 0.1397)
			(layers "F.Cu" "F.Mask" "F.Paste")
			(net "P1V5_C_SENSE")
			(options
				(clearance outline)
				(anchor circle)
			)
			(primitives
				(gr_poly
					(pts
						(arc
							(start -0.1778 -0.2794)
							(mid -0.249642 -0.249642)
							(end -0.2794 -0.1778)
						)
						(arc
							(start -0.2794 0.1778)
							(mid -0.249642 0.249642)
							(end -0.1778 0.2794)
						)
						(arc
							(start 0.1778 0.2794)
							(mid 0.249642 0.249642)
							(end 0.2794 0.1778)
						)
						(arc
							(start 0.2794 -0.1778)
							(mid 0.249642 -0.249642)
							(end 0.1778 -0.2794)
						)
					)
					(width 0)
					(fill yes)
				)
			)
		)
	)
	(footprint ""
		(layer "F.Cu")
		(at 184.42686 -113.64722 90)
		(property "Reference" "R606"
			(at 0 0 90)
			(layer "F.SilkS")
			(hide yes)
			(effects
				(font
					(size 1.27 1.27)
				)
			)
		)
		(property "Value" "10KR2F-2-GP"
			(at 0.064008 -3.993896 90)
			(unlocked yes)
			(layer "F.Fab")
			(hide yes)
			(effects
				(font
					(size 1.016 1.016)
					(thickness 0.1524)
				)
			)
		)
		(property "Device Type" "R402H16"
			(at 0.064008 -5.517896 90)
			(unlocked yes)
			(layer "F.Fab")
			(hide yes)
			(effects
				(font
					(size 1.016 1.016)
					(thickness 0.1524)
				)
			)
		)
		(duplicate_pad_numbers_are_jumpers no)
		(fp_line
			(start 0.508 -0.9398)
			(end -0.508 -0.9398)
			(stroke
				(width 0.1524)
				(type default)
			)
			(layer "F.SilkS")
		)
		(fp_line
			(start -0.508 -0.9398)
			(end -0.508 0.9398)
			(stroke
				(width 0.1524)
				(type default)
			)
			(layer "F.SilkS")
		)
		(fp_rect
			(start -0.508 0.9398)
			(end 0.508 -0.9398)
			(stroke
				(width 0)
				(type default)
			)
			(fill no)
			(layer "F.CrtYd")
		)
		(fp_rect
			(start -0.508 0.9398)
			(end 0.508 -0.9398)
			(stroke
				(width 0)
				(type default)
			)
			(fill no)
			(layer "F.Fab")
		)
		(pad "1" smd custom
			(at 0 -0.4445 90)
			(size 0.1397 0.1397)
			(layers "F.Cu" "F.Mask" "F.Paste")
			(net "P12V_STBY_Q12_G")
			(options
				(clearance outline)
				(anchor circle)
			)
			(primitives
				(gr_poly
					(pts
						(arc
							(start -0.1778 -0.2794)
							(mid -0.249642 -0.249642)
							(end -0.2794 -0.1778)
						)
						(arc
							(start -0.2794 0.1778)
							(mid -0.249642 0.249642)
							(end -0.1778 0.2794)
						)
						(arc
							(start 0.1778 0.2794)
							(mid 0.249642 0.249642)
							(end 0.2794 0.1778)
						)
						(arc
							(start 0.2794 -0.1778)
							(mid 0.249642 -0.249642)
							(end 0.1778 -0.2794)
						)
					)
					(width 0)
					(fill yes)
				)
			)
		)
		(pad "2" smd custom
			(at 0 0.4445 90)
			(size 0.1397 0.1397)
			(layers "F.Cu" "F.Mask" "F.Paste")
			(net "P12V_STBY_SCC")
			(options
				(clearance outline)
				(anchor circle)
			)
			(primitives
				(gr_poly
					(pts
						(arc
							(start -0.1778 -0.2794)
							(mid -0.249642 -0.249642)
							(end -0.2794 -0.1778)
						)
						(arc
							(start -0.2794 0.1778)
							(mid -0.249642 0.249642)
							(end -0.1778 0.2794)
						)
						(arc
							(start 0.1778 0.2794)
							(mid 0.249642 0.249642)
							(end 0.2794 0.1778)
						)
						(arc
							(start 0.2794 -0.1778)
							(mid 0.249642 -0.249642)
							(end 0.1778 -0.2794)
						)
					)
					(width 0)
					(fill yes)
				)
			)
		)
	)
	(footprint ""
		(layer "F.Cu")
		(at 6.5278 -99.1108)
		(property "Reference" "R572"
			(at 0 0 0)
			(layer "F.SilkS")
			(hide yes)
			(effects
				(font
					(size 1.27 1.27)
				)
			)
		)
		(property "Value" "0R2J-2-GP"
			(at 0.064008 -3.993896 0)
			(unlocked yes)
			(layer "F.Fab")
			(hide yes)
			(effects
				(font
					(size 1.016 1.016)
					(thickness 0.1524)
				)
			)
		)
		(property "Device Type" "R402H16"
			(at 0.064008 -5.517896 0)
			(unlocked yes)
			(layer "F.Fab")
			(hide yes)
			(effects
				(font
					(size 1.016 1.016)
					(thickness 0.1524)
				)
			)
		)
		(duplicate_pad_numbers_are_jumpers no)
		(fp_line
			(start -0.508 -0.9398)
			(end -0.508 0.9398)
			(stroke
				(width 0.1524)
				(type default)
			)
			(layer "F.SilkS")
		)
		(fp_line
			(start 0.508 -0.9398)
			(end -0.508 -0.9398)
			(stroke
				(width 0.1524)
				(type default)
			)
			(layer "F.SilkS")
		)
		(fp_rect
			(start -0.508 0.9398)
			(end 0.508 -0.9398)
			(stroke
				(width 0)
				(type default)
			)
			(fill no)
			(layer "F.CrtYd")
		)
		(fp_rect
			(start -0.508 0.9398)
			(end 0.508 -0.9398)
			(stroke
				(width 0)
				(type default)
			)
			(fill no)
			(layer "F.Fab")
		)
		(pad "1" smd custom
			(at 0 -0.4445)
			(size 0.1397 0.1397)
			(layers "F.Cu" "F.Mask" "F.Paste")
			(net "SCC_FULL_PGOOD_BUF_R")
			(options
				(clearance outline)
				(anchor circle)
			)
			(primitives
				(gr_poly
					(pts
						(arc
							(start -0.1778 -0.2794)
							(mid -0.249642 -0.249642)
							(end -0.2794 -0.1778)
						)
						(arc
							(start -0.2794 0.1778)
							(mid -0.249642 0.249642)
							(end -0.1778 0.2794)
						)
						(arc
							(start 0.1778 0.2794)
							(mid 0.249642 0.249642)
							(end 0.2794 0.1778)
						)
						(arc
							(start 0.2794 -0.1778)
							(mid 0.249642 -0.249642)
							(end 0.1778 -0.2794)
						)
					)
					(width 0)
					(fill yes)
				)
			)
		)
		(pad "2" smd custom
			(at 0 0.4445)
			(size 0.1397 0.1397)
			(layers "F.Cu" "F.Mask" "F.Paste")
			(net "SCC_FULL_PGOOD_BUF")
			(options
				(clearance outline)
				(anchor circle)
			)
			(primitives
				(gr_poly
					(pts
						(arc
							(start -0.1778 -0.2794)
							(mid -0.249642 -0.249642)
							(end -0.2794 -0.1778)
						)
						(arc
							(start -0.2794 0.1778)
							(mid -0.249642 0.249642)
							(end -0.1778 0.2794)
						)
						(arc
							(start 0.1778 0.2794)
							(mid 0.249642 0.249642)
							(end 0.2794 0.1778)
						)
						(arc
							(start 0.2794 -0.1778)
							(mid 0.249642 -0.249642)
							(end 0.1778 -0.2794)
						)
					)
					(width 0)
					(fill yes)
				)
			)
		)
	)
	(footprint ""
		(layer "F.Cu")
		(at 190.23838 -76.61148 90)
		(property "Reference" "R370"
			(at 0 0 90)
			(layer "F.SilkS")
			(hide yes)
			(effects
				(font
					(size 1.27 1.27)
				)
			)
		)
		(property "Value" "4K7R2F-GP"
			(at 0.064008 -3.993896 90)
			(unlocked yes)
			(layer "F.Fab")
			(hide yes)
			(effects
				(font
					(size 1.016 1.016)
					(thickness 0.1524)
				)
			)
		)
		(property "Device Type" "R402H16"
			(at 0.064008 -5.517896 90)
			(unlocked yes)
			(layer "F.Fab")
			(hide yes)
			(effects
				(font
					(size 1.016 1.016)
					(thickness 0.1524)
				)
			)
		)
		(duplicate_pad_numbers_are_jumpers no)
		(fp_line
			(start 0.508 -0.9398)
			(end -0.508 -0.9398)
			(stroke
				(width 0.1524)
				(type default)
			)
			(layer "F.SilkS")
		)
		(fp_line
			(start -0.508 -0.9398)
			(end -0.508 0.9398)
			(stroke
				(width 0.1524)
				(type default)
			)
			(layer "F.SilkS")
		)
		(fp_rect
			(start -0.508 0.9398)
			(end 0.508 -0.9398)
			(stroke
				(width 0)
				(type default)
			)
			(fill no)
			(layer "F.CrtYd")
		)
		(fp_rect
			(start -0.508 0.9398)
			(end 0.508 -0.9398)
			(stroke
				(width 0)
				(type default)
			)
			(fill no)
			(layer "F.Fab")
		)
		(pad "1" smd custom
			(at 0 -0.4445 90)
			(size 0.1397 0.1397)
			(layers "F.Cu" "F.Mask" "F.Paste")
			(net "TEMP2_A0")
			(options
				(clearance outline)
				(anchor circle)
			)
			(primitives
				(gr_poly
					(pts
						(arc
							(start -0.1778 -0.2794)
							(mid -0.249642 -0.249642)
							(end -0.2794 -0.1778)
						)
						(arc
							(start -0.2794 0.1778)
							(mid -0.249642 0.249642)
							(end -0.1778 0.2794)
						)
						(arc
							(start 0.1778 0.2794)
							(mid 0.249642 0.249642)
							(end 0.2794 0.1778)
						)
						(arc
							(start 0.2794 -0.1778)
							(mid 0.249642 -0.249642)
							(end 0.1778 -0.2794)
						)
					)
					(width 0)
					(fill yes)
				)
			)
		)
		(pad "2" smd custom
			(at 0 0.4445 90)
			(size 0.1397 0.1397)
			(layers "F.Cu" "F.Mask" "F.Paste")
			(net "GND")
			(options
				(clearance outline)
				(anchor circle)
			)
			(primitives
				(gr_poly
					(pts
						(arc
							(start -0.1778 -0.2794)
							(mid -0.249642 -0.249642)
							(end -0.2794 -0.1778)
						)
						(arc
							(start -0.2794 0.1778)
							(mid -0.249642 0.249642)
							(end -0.1778 0.2794)
						)
						(arc
							(start 0.1778 0.2794)
							(mid 0.249642 0.249642)
							(end 0.2794 0.1778)
						)
						(arc
							(start 0.2794 -0.1778)
							(mid 0.249642 -0.249642)
							(end 0.1778 -0.2794)
						)
					)
					(width 0)
					(fill yes)
				)
			)
		)
	)
)
